(kicad_pcb
	(version 20241229)
	(generator "pcbnew")
	(generator_version "9.0")
	(general
		(thickness 1.292)
		(legacy_teardrops no)
	)
	(paper "A4")
	(title_block
		(title "LPDDR5 Testbed")
		(date "2023-12-19")
		(rev "1.0.0")
		(comment 9 "footprints 31-36 of 160")
	)
	(layers
		(0 "F.Cu" signal)
		(4 "In1.Cu" power)
		(6 "In2.Cu" power)
		(8 "In3.Cu" signal)
		(10 "In4.Cu" signal)
		(2 "B.Cu" signal)
		(9 "F.Adhes" user "F.Adhesive")
		(11 "B.Adhes" user "B.Adhesive")
		(13 "F.Paste" user)
		(15 "B.Paste" user)
		(5 "F.SilkS" user "F.Silkscreen")
		(7 "B.SilkS" user "B.Silkscreen")
		(1 "F.Mask" user)
		(3 "B.Mask" user)
		(17 "Dwgs.User" user "User.Drawings")
		(19 "Cmts.User" user "User.Comments")
		(21 "Eco1.User" user "User.Eco1")
		(23 "Eco2.User" user "User.Eco2")
		(25 "Edge.Cuts" user)
		(27 "Margin" user)
		(31 "F.CrtYd" user "F.Courtyard")
		(29 "B.CrtYd" user "B.Courtyard")
		(35 "F.Fab" user)
		(33 "B.Fab" user)
	)
	(footprint "antmicro-footprints:R_0402_1005Metric"
		(layer "F.Cu")
		(at 111.4 65.625 90)
		(descr "Resistor SMD 0402")
		(tags "resistor SMD 0402")
		(property "Reference" "R36"
			(at -2.975 0.4 90)
			(unlocked yes)
			(layer "F.SilkS")
			(effects
				(font
					(size 0.7 0.7)
					(thickness 0.15)
				)
				(justify left bottom)
			)
		)
		(property "Value" "R_200k_0402"
			(at -1.011843 1.772047 90)
			(layer "F.Fab")
			(effects
				(font
					(size 0.7 0.7)
					(thickness 0.15)
				)
				(justify left bottom)
			)
		)
		(property "Author" "Antmicro"
			(at 177.025 -45.775 0)
			(layer "F.Fab")
			(hide yes)
			(effects
				(font
					(size 1 1)
					(thickness 0.15)
				)
			)
		)
		(property "License" "Apache-2.0"
			(at 177.025 -45.775 0)
			(layer "F.Fab")
			(hide yes)
			(effects
				(font
					(size 1 1)
					(thickness 0.15)
				)
			)
		)
		(property "MPN" "CR0402-FX-2003GLF"
			(at 177.025 -45.775 0)
			(layer "F.Fab")
			(hide yes)
			(effects
				(font
					(size 1 1)
					(thickness 0.15)
				)
			)
		)
		(property "Manufacturer" "Bourns"
			(at 177.025 -45.775 0)
			(layer "F.Fab")
			(hide yes)
			(effects
				(font
					(size 1 1)
					(thickness 0.15)
				)
			)
		)
		(property "Tolerance" "1%"
			(at 177.025 -45.775 0)
			(layer "F.Fab")
			(hide yes)
			(effects
				(font
					(size 1 1)
					(thickness 0.15)
				)
			)
		)
		(property "Val" "200k"
			(at 177.025 -45.775 0)
			(layer "F.Fab")
			(hide yes)
			(effects
				(font
					(size 1 1)
					(thickness 0.15)
				)
			)
		)
		(sheetname "Power supply")
		(sheetfile "power_supply.kicad_sch")
		(attr smd)
		(fp_rect
			(start -0.93 -0.47)
			(end 0.93 0.47)
			(stroke
				(width 0.05)
				(type solid)
			)
			(fill no)
			(layer "F.CrtYd")
		)
		(fp_rect
			(start -0.5 -0.25)
			(end 0.5 0.25)
			(stroke
				(width 0.15)
				(type solid)
			)
			(fill no)
			(layer "F.Fab")
		)
		(pad "1" smd roundrect
			(at -0.485 0 90)
			(size 0.59 0.64)
			(layers "F.Cu" "F.Mask" "F.Paste")
			(roundrect_rratio 0.25)
			(net 71 "/Power supply/FB2")
			(pintype "passive")
		)
		(pad "2" smd roundrect
			(at 0.485 0 90)
			(size 0.59 0.64)
			(layers "F.Cu" "F.Mask" "F.Paste")
			(roundrect_rratio 0.25)
			(net 14 "GND")
			(pintype "passive")
		)
	)
	(footprint "antmicro-footprints:C_0603_1608Metric"
		(layer "F.Cu")
		(at 108.025 62.575)
		(descr "Capacitor SMD 0603")
		(tags "capacitor 0603")
		(property "Reference" "C17"
			(at -1.125 1.325 0)
			(unlocked yes)
			(layer "F.SilkS")
			(effects
				(font
					(size 0.7 0.7)
					(thickness 0.15)
				)
				(justify left bottom)
			)
		)
		(property "Value" "C_22u_0603"
			(at -1.42757 1.770288 0)
			(layer "F.Fab")
			(effects
				(font
					(size 0.7 0.7)
					(thickness 0.15)
				)
				(justify left bottom)
			)
		)
		(property "Author" "Antmicro"
			(at 0 0 0)
			(layer "F.Fab")
			(hide yes)
			(effects
				(font
					(size 1 1)
					(thickness 0.15)
				)
			)
		)
		(property "Dielectric" ""
			(at 0 0 0)
			(layer "F.Fab")
			(hide yes)
			(effects
				(font
					(size 1 1)
					(thickness 0.15)
				)
			)
		)
		(property "License" "Apache-2.0"
			(at 0 0 0)
			(layer "F.Fab")
			(hide yes)
			(effects
				(font
					(size 1 1)
					(thickness 0.15)
				)
			)
		)
		(property "MPN" "GRM188R60J226MEA0D"
			(at 0 0 0)
			(layer "F.Fab")
			(hide yes)
			(effects
				(font
					(size 1 1)
					(thickness 0.15)
				)
			)
		)
		(property "Manufacturer" "Murata"
			(at 0 0 0)
			(layer "F.Fab")
			(hide yes)
			(effects
				(font
					(size 1 1)
					(thickness 0.15)
				)
			)
		)
		(property "Val" "22u"
			(at 0 0 0)
			(layer "F.Fab")
			(hide yes)
			(effects
				(font
					(size 1 1)
					(thickness 0.15)
				)
			)
		)
		(property "Voltage" ""
			(at 0 0 0)
			(layer "F.Fab")
			(hide yes)
			(effects
				(font
					(size 1 1)
					(thickness 0.15)
				)
			)
		)
		(sheetname "Power supply")
		(sheetfile "power_supply.kicad_sch")
		(attr smd)
		(fp_line
			(start -0.3 -0.3)
			(end 0.3 -0.3)
			(stroke
				(width 0.15)
				(type solid)
			)
			(layer "F.SilkS")
		)
		(fp_line
			(start -0.3 0.3)
			(end 0.3 0.3)
			(stroke
				(width 0.15)
				(type solid)
			)
			(layer "F.SilkS")
		)
		(fp_rect
			(start -1.24 -0.7)
			(end 1.24 0.7)
			(stroke
				(width 0.05)
				(type solid)
			)
			(fill no)
			(layer "F.CrtYd")
		)
		(fp_rect
			(start -0.8 -0.4)
			(end 0.8 0.4)
			(stroke
				(width 0.15)
				(type solid)
			)
			(fill no)
			(layer "F.Fab")
		)
		(pad "1" smd roundrect
			(at -0.7 0)
			(size 0.6 0.8)
			(layers "F.Cu" "F.Mask" "F.Paste")
			(roundrect_rratio 0.2)
			(net 14 "GND")
			(pintype "passive")
		)
		(pad "2" smd roundrect
			(at 0.7 0)
			(size 0.6 0.8)
			(layers "F.Cu" "F.Mask" "F.Paste")
			(roundrect_rratio 0.2)
			(net 8 "/Power supply/VOUT2")
			(pintype "passive")
		)
	)
	(footprint "antmicro-footprints:C_0402_1005Metric"
		(layer "F.Cu")
		(at 162.475 71.65)
		(descr "Capacitor SMD 0402")
		(tags "capacitor SMD 0402")
		(property "Reference" "C9"
			(at -0.975 2.65 0)
			(unlocked yes)
			(layer "F.SilkS")
			(effects
				(font
					(size 0.7 0.7)
					(thickness 0.15)
				)
				(justify left bottom)
			)
		)
		(property "Value" "C_4u7_0402"
			(at -1.022927 2.155213 0)
			(layer "F.Fab")
			(effects
				(font
					(size 0.7 0.7)
					(thickness 0.15)
				)
				(justify left bottom)
			)
		)
		(property "Author" "Antmicro"
			(at 0 0 0)
			(layer "F.Fab")
			(hide yes)
			(effects
				(font
					(size 1 1)
					(thickness 0.15)
				)
			)
		)
		(property "Dielectric" ""
			(at 0 0 0)
			(layer "F.Fab")
			(hide yes)
			(effects
				(font
					(size 1 1)
					(thickness 0.15)
				)
			)
		)
		(property "License" "Apache-2.0"
			(at 0 0 0)
			(layer "F.Fab")
			(hide yes)
			(effects
				(font
					(size 1 1)
					(thickness 0.15)
				)
			)
		)
		(property "MPN" "GRM155R61A475MEAAD"
			(at 0 0 0)
			(layer "F.Fab")
			(hide yes)
			(effects
				(font
					(size 1 1)
					(thickness 0.15)
				)
			)
		)
		(property "Manufacturer" "Murata"
			(at 0 0 0)
			(layer "F.Fab")
			(hide yes)
			(effects
				(font
					(size 1 1)
					(thickness 0.15)
				)
			)
		)
		(property "Val" "4u7"
			(at 0 0 0)
			(layer "F.Fab")
			(hide yes)
			(effects
				(font
					(size 1 1)
					(thickness 0.15)
				)
			)
		)
		(property "Voltage" ""
			(at 0 0 0)
			(layer "F.Fab")
			(hide yes)
			(effects
				(font
					(size 1 1)
					(thickness 0.15)
				)
			)
		)
		(sheetname "Power supply")
		(sheetfile "power_supply.kicad_sch")
		(attr smd)
		(fp_rect
			(start -0.9659 -0.481258)
			(end 0.9649 0.458742)
			(stroke
				(width 0.05)
				(type solid)
			)
			(fill no)
			(layer "F.CrtYd")
		)
		(fp_line
			(start -0.499 -0.25)
			(end 0.499 -0.25)
			(stroke
				(width 0.15)
				(type solid)
			)
			(layer "F.Fab")
		)
		(fp_line
			(start -0.499 0.248)
			(end -0.499 -0.25)
			(stroke
				(width 0.15)
				(type solid)
			)
			(layer "F.Fab")
		)
		(fp_line
			(start 0.499 -0.25)
			(end 0.499 0.248)
			(stroke
				(width 0.15)
				(type solid)
			)
			(layer "F.Fab")
		)
		(fp_line
			(start 0.499 0.248)
			(end -0.499 0.248)
			(stroke
				(width 0.15)
				(type solid)
			)
			(layer "F.Fab")
		)
		(pad "1" smd roundrect
			(at -0.484 0)
			(size 0.59 0.64)
			(layers "F.Cu" "F.Mask" "F.Paste")
			(roundrect_rratio 0.25)
			(net 14 "GND")
			(pintype "passive")
		)
		(pad "2" smd roundrect
			(at 0.484 0)
			(size 0.59 0.64)
			(layers "F.Cu" "F.Mask" "F.Paste")
			(roundrect_rratio 0.25)
			(net 1 "+1V1")
			(pintype "passive")
		)
	)
	(footprint "antmicro-footprints:C_0402_1005Metric"
		(layer "F.Cu")
		(at 125.6 78.95 90)
		(descr "Capacitor SMD 0402")
		(tags "capacitor SMD 0402")
		(property "Reference" "C63"
			(at 0.95 0.325 90)
			(unlocked yes)
			(layer "F.SilkS")
			(effects
				(font
					(size 0.7 0.7)
					(thickness 0.15)
				)
				(justify left bottom)
			)
		)
		(property "Value" "C_4u7_0402"
			(at -1.022927 2.155213 90)
			(layer "F.Fab")
			(effects
				(font
					(size 0.7 0.7)
					(thickness 0.15)
				)
				(justify left bottom)
			)
		)
		(property "Author" "Antmicro"
			(at 204.55 -46.65 0)
			(layer "F.Fab")
			(hide yes)
			(effects
				(font
					(size 1 1)
					(thickness 0.15)
				)
			)
		)
		(property "Dielectric" ""
			(at 204.55 -46.65 0)
			(layer "F.Fab")
			(hide yes)
			(effects
				(font
					(size 1 1)
					(thickness 0.15)
				)
			)
		)
		(property "License" "Apache-2.0"
			(at 204.55 -46.65 0)
			(layer "F.Fab")
			(hide yes)
			(effects
				(font
					(size 1 1)
					(thickness 0.15)
				)
			)
		)
		(property "MPN" "GRM155R61A475MEAAD"
			(at 204.55 -46.65 0)
			(layer "F.Fab")
			(hide yes)
			(effects
				(font
					(size 1 1)
					(thickness 0.15)
				)
			)
		)
		(property "Manufacturer" "Murata"
			(at 204.55 -46.65 0)
			(layer "F.Fab")
			(hide yes)
			(effects
				(font
					(size 1 1)
					(thickness 0.15)
				)
			)
		)
		(property "Val" "4u7"
			(at 204.55 -46.65 0)
			(layer "F.Fab")
			(hide yes)
			(effects
				(font
					(size 1 1)
					(thickness 0.15)
				)
			)
		)
		(property "Voltage" ""
			(at 204.55 -46.65 0)
			(layer "F.Fab")
			(hide yes)
			(effects
				(font
					(size 1 1)
					(thickness 0.15)
				)
			)
		)
		(sheetname "LPDDR5")
		(sheetfile "lpddr5.kicad_sch")
		(attr smd)
		(fp_rect
			(start -0.9659 -0.481258)
			(end 0.9649 0.458742)
			(stroke
				(width 0.05)
				(type solid)
			)
			(fill no)
			(layer "F.CrtYd")
		)
		(fp_line
			(start 0.499 -0.25)
			(end 0.499 0.248)
			(stroke
				(width 0.15)
				(type solid)
			)
			(layer "F.Fab")
		)
		(fp_line
			(start -0.499 -0.25)
			(end 0.499 -0.25)
			(stroke
				(width 0.15)
				(type solid)
			)
			(layer "F.Fab")
		)
		(fp_line
			(start 0.499 0.248)
			(end -0.499 0.248)
			(stroke
				(width 0.15)
				(type solid)
			)
			(layer "F.Fab")
		)
		(fp_line
			(start -0.499 0.248)
			(end -0.499 -0.25)
			(stroke
				(width 0.15)
				(type solid)
			)
			(layer "F.Fab")
		)
		(pad "1" smd roundrect
			(at -0.484 0 90)
			(size 0.59 0.64)
			(layers "F.Cu" "F.Mask" "F.Paste")
			(roundrect_rratio 0.25)
			(net 14 "GND")
			(pintype "passive")
		)
		(pad "2" smd roundrect
			(at 0.484 0 90)
			(size 0.59 0.64)
			(layers "F.Cu" "F.Mask" "F.Paste")
			(roundrect_rratio 0.25)
			(net 12 "+0V9")
			(pintype "passive")
		)
	)
	(footprint "antmicro-footprints:R_Array_4x0402_Panasonic_EXB28V"
		(layer "F.Cu")
		(at 127.7 93.8)
		(property "Reference" "R7"
			(at -0.7 -1.4 0)
			(unlocked yes)
			(layer "F.SilkS")
			(effects
				(font
					(size 0.7 0.7)
					(thickness 0.15)
				)
				(justify left bottom)
			)
		)
		(property "Value" "R_4x100R_0402_array"
			(at -1.5 2 0)
			(layer "F.Fab")
			(effects
				(font
					(size 0.7 0.7)
					(thickness 0.15)
				)
				(justify left bottom)
			)
		)
		(property "Author" "Antmicro"
			(at 0 0 0)
			(layer "F.Fab")
			(hide yes)
			(effects
				(font
					(size 1 1)
					(thickness 0.15)
				)
			)
		)
		(property "License" "Apache-2.0"
			(at 0 0 0)
			(layer "F.Fab")
			(hide yes)
			(effects
				(font
					(size 1 1)
					(thickness 0.15)
				)
			)
		)
		(property "MPN" "EXB-28V101JX"
			(at 0 0 0)
			(layer "F.Fab")
			(hide yes)
			(effects
				(font
					(size 1 1)
					(thickness 0.15)
				)
			)
		)
		(property "Manufacturer" "Panasonic"
			(at 0 0 0)
			(layer "F.Fab")
			(hide yes)
			(effects
				(font
					(size 1 1)
					(thickness 0.15)
				)
			)
		)
		(property "Val" "R_4x100R_0402"
			(at 0 0 0)
			(layer "F.Fab")
			(hide yes)
			(effects
				(font
					(size 1 1)
					(thickness 0.15)
				)
			)
		)
		(sheetname "Translators")
		(sheetfile "translators.kicad_sch")
		(attr smd)
		(fp_line
			(start -1.25 -0.5)
			(end -1.25 0.498)
			(stroke
				(width 0.15)
				(type solid)
			)
			(layer "F.SilkS")
		)
		(fp_line
			(start 1.25 0.499)
			(end 1.25 -0.499)
			(stroke
				(width 0.15)
				(type solid)
			)
			(layer "F.SilkS")
		)
		(fp_rect
			(start -1.25 -0.8)
			(end 1.25 0.8)
			(stroke
				(width 0.05)
				(type solid)
			)
			(fill no)
			(layer "F.CrtYd")
		)
		(fp_line
			(start -1 -0.5)
			(end 0.998 -0.5)
			(stroke
				(width 0.15)
				(type solid)
			)
			(layer "F.Fab")
		)
		(fp_line
			(start -1 0.498)
			(end -1 -0.5)
			(stroke
				(width 0.15)
				(type solid)
			)
			(layer "F.Fab")
		)
		(fp_line
			(start 0.998 -0.5)
			(end 0.998 0.498)
			(stroke
				(width 0.15)
				(type solid)
			)
			(layer "F.Fab")
		)
		(fp_line
			(start 0.998 0.498)
			(end -1 0.498)
			(stroke
				(width 0.15)
				(type solid)
			)
			(layer "F.Fab")
		)
		(pad "1" smd roundrect
			(at -0.8875 0.45)
			(size 0.525 0.5)
			(layers "F.Cu" "F.Mask" "F.Paste")
			(roundrect_rratio 0.25)
			(net 165 "/SODIMM/LPDDR5_IN_A.CS0")
			(pinfunction "R1.1")
			(pintype "passive")
		)
		(pad "2" smd roundrect
			(at -0.25 0.45)
			(size 0.25 0.5)
			(layers "F.Cu" "F.Mask" "F.Paste")
			(roundrect_rratio 0.25)
			(net 162 "/SODIMM/LPDDR5_IN_A.CS1")
			(pinfunction "R2.1")
			(pintype "passive")
		)
		(pad "3" smd roundrect
			(at 0.25 0.45)
			(size 0.25 0.5)
			(layers "F.Cu" "F.Mask" "F.Paste")
			(roundrect_rratio 0.25)
			(net 164 "/SODIMM/LPDDR5_IN_A.CA0")
			(pinfunction "R3.1")
			(pintype "passive")
		)
		(pad "4" smd roundrect
			(at 0.8875 0.45)
			(size 0.525 0.5)
			(layers "F.Cu" "F.Mask" "F.Paste")
			(roundrect_rratio 0.25)
			(net 163 "/SODIMM/LPDDR5_IN_A.CA1")
			(pinfunction "R4.1")
			(pintype "passive")
		)
		(pad "5" smd roundrect
			(at 0.8875 -0.45)
			(size 0.525 0.5)
			(layers "F.Cu" "F.Mask" "F.Paste")
			(roundrect_rratio 0.25)
			(net 58 "/LPDDR5/LPDDR5_A.CA1")
			(pinfunction "R4.2")
			(pintype "passive")
		)
		(pad "6" smd roundrect
			(at 0.25 -0.45)
			(size 0.25 0.5)
			(layers "F.Cu" "F.Mask" "F.Paste")
			(roundrect_rratio 0.25)
			(net 57 "/LPDDR5/LPDDR5_A.CA0")
			(pinfunction "R3.2")
			(pintype "passive")
		)
		(pad "7" smd roundrect
			(at -0.25 -0.45)
			(size 0.25 0.5)
			(layers "F.Cu" "F.Mask" "F.Paste")
			(roundrect_rratio 0.25)
			(net 44 "/LPDDR5/LPDDR5_A.CS1")
			(pinfunction "R2.2")
			(pintype "passive")
		)
		(pad "8" smd roundrect
			(at -0.8875 -0.45)
			(size 0.525 0.5)
			(layers "F.Cu" "F.Mask" "F.Paste")
			(roundrect_rratio 0.25)
			(net 43 "/LPDDR5/LPDDR5_A.CS0")
			(pinfunction "R1.2")
			(pintype "passive")
		)
	)
	(footprint "antmicro-footprints:C_0402_1005Metric"
		(layer "F.Cu")
		(at 133.675 88.275)
		(descr "Capacitor SMD 0402")
		(tags "capacitor SMD 0402")
		(property "Reference" "C58"
			(at -3.275 0.25 0)
			(unlocked yes)
			(layer "F.SilkS")
			(effects
				(font
					(size 0.7 0.7)
					(thickness 0.15)
				)
				(justify left bottom)
			)
		)
		(property "Value" "C_4u7_0402"
			(at -1.022927 2.155213 0)
			(layer "F.Fab")
			(effects
				(font
					(size 0.7 0.7)
					(thickness 0.15)
				)
				(justify left bottom)
			)
		)
		(property "Author" "Antmicro"
			(at 0 0 0)
			(layer "F.Fab")
			(hide yes)
			(effects
				(font
					(size 1 1)
					(thickness 0.15)
				)
			)
		)
		(property "Dielectric" ""
			(at 0 0 0)
			(layer "F.Fab")
			(hide yes)
			(effects
				(font
					(size 1 1)
					(thickness 0.15)
				)
			)
		)
		(property "License" "Apache-2.0"
			(at 0 0 0)
			(layer "F.Fab")
			(hide yes)
			(effects
				(font
					(size 1 1)
					(thickness 0.15)
				)
			)
		)
		(property "MPN" "GRM155R61A475MEAAD"
			(at 0 0 0)
			(layer "F.Fab")
			(hide yes)
			(effects
				(font
					(size 1 1)
					(thickness 0.15)
				)
			)
		)
		(property "Manufacturer" "Murata"
			(at 0 0 0)
			(layer "F.Fab")
			(hide yes)
			(effects
				(font
					(size 1 1)
					(thickness 0.15)
				)
			)
		)
		(property "Val" "4u7"
			(at 0 0 0)
			(layer "F.Fab")
			(hide yes)
			(effects
				(font
					(size 1 1)
					(thickness 0.15)
				)
			)
		)
		(property "Voltage" ""
			(at 0 0 0)
			(layer "F.Fab")
			(hide yes)
			(effects
				(font
					(size 1 1)
					(thickness 0.15)
				)
			)
		)
		(sheetname "LPDDR5")
		(sheetfile "lpddr5.kicad_sch")
		(attr smd)
		(fp_rect
			(start -0.9659 -0.481258)
			(end 0.9649 0.458742)
			(stroke
				(width 0.05)
				(type solid)
			)
			(fill no)
			(layer "F.CrtYd")
		)
		(fp_line
			(start -0.499 -0.25)
			(end 0.499 -0.25)
			(stroke
				(width 0.15)
				(type solid)
			)
			(layer "F.Fab")
		)
		(fp_line
			(start -0.499 0.248)
			(end -0.499 -0.25)
			(stroke
				(width 0.15)
				(type solid)
			)
			(layer "F.Fab")
		)
		(fp_line
			(start 0.499 -0.25)
			(end 0.499 0.248)
			(stroke
				(width 0.15)
				(type solid)
			)
			(layer "F.Fab")
		)
		(fp_line
			(start 0.499 0.248)
			(end -0.499 0.248)
			(stroke
				(width 0.15)
				(type solid)
			)
			(layer "F.Fab")
		)
		(pad "1" smd roundrect
			(at -0.484 0)
			(size 0.59 0.64)
			(layers "F.Cu" "F.Mask" "F.Paste")
			(roundrect_rratio 0.25)
			(net 14 "GND")
			(pintype "passive")
		)
		(pad "2" smd roundrect
			(at 0.484 0)
			(size 0.59 0.64)
			(layers "F.Cu" "F.Mask" "F.Paste")
			(roundrect_rratio 0.25)
			(net 13 "+1V05")
			(pintype "passive")
		)
	)
)
